(kicad_pcb
	(version 20241229)
	(generator "pcbnew")
	(generator_version "9.0")
	(general
		(thickness 1.62)
		(legacy_teardrops no)
	)
	(paper "A4")
	(title_block
		(title "OCuLink to 10GbE adapter")
		(date "2026-02-23")
		(rev "1.1.0")
		(company "Antmicro Ltd")
		(comment 1 "www.antmicro.com")
		(comment 9 "footprints 96-101 of 510")
	)
	(layers
		(0 "F.Cu" signal)
		(4 "In1.Cu" signal)
		(6 "In2.Cu" signal)
		(8 "In3.Cu" signal)
		(10 "In4.Cu" signal)
		(12 "In5.Cu" signal)
		(14 "In6.Cu" signal)
		(2 "B.Cu" signal)
		(9 "F.Adhes" user "F.Adhesive")
		(11 "B.Adhes" user "B.Adhesive")
		(13 "F.Paste" user)
		(15 "B.Paste" user)
		(5 "F.SilkS" user "F.Silkscreen")
		(7 "B.SilkS" user "B.Silkscreen")
		(1 "F.Mask" user)
		(3 "B.Mask" user)
		(17 "Dwgs.User" user "User.Drawings")
		(19 "Cmts.User" user "User.Comments")
		(21 "Eco1.User" user "User.Eco1")
		(23 "Eco2.User" user "User.Eco2")
		(25 "Edge.Cuts" user)
		(27 "Margin" user)
		(31 "F.CrtYd" user "F.Courtyard")
		(29 "B.CrtYd" user "B.Courtyard")
		(35 "F.Fab" user)
		(33 "B.Fab" user)
	)
	(footprint "antmicro-footprints:SW_DS04-254-1-01BK-SMT"
		(layer "F.Cu")
		(at 117.1 94.4 -90)
		(property "Reference" "SW1"
			(at -5.61 -0.89 90)
			(layer "F.SilkS")
			(effects
				(font
					(size 0.7 0.7)
					(thickness 0.15)
				)
				(justify right top)
			)
		)
		(property "Value" "SW_DS04-254-1-01BK-SMT"
			(at 0 3 90)
			(layer "F.Fab")
			(hide yes)
			(effects
				(font
					(size 0.7 0.7)
					(thickness 0.15)
				)
				(justify right top)
			)
		)
		(property "Datasheet" "https://www.mouser.com/datasheet/2/670/ds04_254_smt-1777718.pdf"
			(at 0 0 90)
			(layer "F.Fab")
			(hide yes)
			(effects
				(font
					(size 1.27 1.27)
					(thickness 0.15)
				)
			)
		)
		(property "Description" "Slide switch"
			(at 0 0 90)
			(layer "F.Fab")
			(hide yes)
			(effects
				(font
					(size 1.27 1.27)
					(thickness 0.15)
				)
			)
		)
		(property "MPN" "DS04-254-1-01BK-SMT"
			(at 0 0 270)
			(unlocked yes)
			(layer "F.Fab")
			(hide yes)
			(effects
				(font
					(size 1 1)
					(thickness 0.15)
				)
			)
		)
		(property "Manufacturer" "CUI Inc"
			(at 0 0 270)
			(unlocked yes)
			(layer "F.Fab")
			(hide yes)
			(effects
				(font
					(size 1 1)
					(thickness 0.15)
				)
			)
		)
		(property "Author" "Antmicro"
			(at 0 0 270)
			(unlocked yes)
			(layer "F.Fab")
			(hide yes)
			(effects
				(font
					(size 1 1)
					(thickness 0.15)
				)
			)
		)
		(property "License" "Apache-2.0"
			(at 0 0 270)
			(unlocked yes)
			(layer "F.Fab")
			(hide yes)
			(effects
				(font
					(size 1 1)
					(thickness 0.15)
				)
			)
		)
		(property ki_fp_filters "SW?DIP?x1*")
		(sheetname "/X710-AT2 RSVD/")
		(sheetfile "x710-at2-rsvd.kicad_sch")
		(attr smd)
		(fp_rect
			(start -3.3 -2)
			(end 3.3 2)
			(stroke
				(width 0.15)
				(type solid)
			)
			(fill no)
			(layer "F.SilkS")
		)
		(fp_rect
			(start -5.25 -2.025)
			(end 5.25 2.025)
			(stroke
				(width 0.05)
				(type solid)
			)
			(fill no)
			(layer "F.CrtYd")
		)
		(fp_rect
			(start -3.1 -1.8)
			(end 3.1 1.8)
			(stroke
				(width 0.15)
				(type solid)
			)
			(fill no)
			(layer "F.Fab")
		)
		(pad "1" smd rect
			(at -4.472 0.038 270)
			(size 1.5 1.1)
			(layers "F.Cu" "F.Mask" "F.Paste")
			(net 114 "/X710-AT2 RSVD/DEBUG_EN")
			(pintype "passive")
		)
		(pad "2" smd rect
			(at 4.428 0.038 90)
			(size 1.5 1.1)
			(layers "F.Cu" "F.Mask" "F.Paste")
			(net 7 "+3V3")
			(pintype "passive")
		)
	)
	(footprint "antmicro-footprints:C_0805_2012Metric"
		(layer "F.Cu")
		(at 71.3 114.3 90)
		(descr "Capacitor SMD 0805")
		(tags "capacitor SMD 0805")
		(property "Reference" "C172"
			(at -2.37 4.38 90)
			(layer "F.SilkS")
			(effects
				(font
					(size 0.7 0.7)
					(thickness 0.15)
				)
				(justify left bottom)
			)
		)
		(property "Value" "C_100u_0805"
			(at -2.055717 1.963153 90)
			(layer "F.Fab")
			(hide yes)
			(effects
				(font
					(size 0.7 0.7)
					(thickness 0.15)
				)
				(justify left bottom)
			)
		)
		(property "Datasheet" "https://www.murata.com/products/productdetail?partno=GRM21BR60J107ME15%23"
			(at 0 0 90)
			(layer "F.Fab")
			(hide yes)
			(effects
				(font
					(size 1.27 1.27)
					(thickness 0.15)
				)
			)
		)
		(property "Description" "SMD Multilayer Ceramic Capacitor, 100 µF, 6.3 V, 0805 [2012 Metric], ± 20%, X5R, GRM Series"
			(at 0 0 90)
			(layer "F.Fab")
			(hide yes)
			(effects
				(font
					(size 1.27 1.27)
					(thickness 0.15)
				)
			)
		)
		(property "MPN" "GRM21BR60J107ME15L"
			(at 0 0 90)
			(unlocked yes)
			(layer "F.Fab")
			(hide yes)
			(effects
				(font
					(size 1 1)
					(thickness 0.15)
				)
			)
		)
		(property "Manufacturer" "Murata"
			(at 0 0 90)
			(unlocked yes)
			(layer "F.Fab")
			(hide yes)
			(effects
				(font
					(size 1 1)
					(thickness 0.15)
				)
			)
		)
		(property "License" "Apache-2.0"
			(at 0 0 90)
			(unlocked yes)
			(layer "F.Fab")
			(hide yes)
			(effects
				(font
					(size 1 1)
					(thickness 0.15)
				)
			)
		)
		(property "Author" "Antmicro"
			(at 0 0 90)
			(unlocked yes)
			(layer "F.Fab")
			(hide yes)
			(effects
				(font
					(size 1 1)
					(thickness 0.15)
				)
			)
		)
		(property "Val" "100u"
			(at 0 0 90)
			(unlocked yes)
			(layer "F.Fab")
			(hide yes)
			(effects
				(font
					(size 1 1)
					(thickness 0.15)
				)
			)
		)
		(property "Voltage" ""
			(at 0 0 90)
			(unlocked yes)
			(layer "F.Fab")
			(hide yes)
			(effects
				(font
					(size 1 1)
					(thickness 0.15)
				)
			)
		)
		(property "Dielectric" ""
			(at 0 0 90)
			(unlocked yes)
			(layer "F.Fab")
			(hide yes)
			(effects
				(font
					(size 1 1)
					(thickness 0.15)
				)
			)
		)
		(property "Public" "False"
			(at 0 0 90)
			(unlocked yes)
			(layer "F.Fab")
			(hide yes)
			(effects
				(font
					(size 1 1)
					(thickness 0.15)
				)
			)
		)
		(sheetname "/X710-AT2 power/")
		(sheetfile "x710-at2-power.kicad_sch")
		(attr smd)
		(fp_line
			(start -0.3 -0.7)
			(end 0.3 -0.7)
			(stroke
				(width 0.15)
				(type solid)
			)
			(layer "F.SilkS")
		)
		(fp_line
			(start -0.3 0.7)
			(end 0.3 0.7)
			(stroke
				(width 0.15)
				(type solid)
			)
			(layer "F.SilkS")
		)
		(fp_rect
			(start 1.95 -0.9)
			(end -1.95 0.9)
			(stroke
				(width 0.05)
				(type default)
			)
			(fill no)
			(layer "F.CrtYd")
		)
		(fp_rect
			(start -0.95 -0.675)
			(end 0.95 0.675)
			(stroke
				(width 0.15)
				(type solid)
			)
			(fill no)
			(layer "F.Fab")
		)
		(pad "1" smd roundrect
			(at -1.1 0 90)
			(size 1.2 1.3)
			(layers "F.Cu" "F.Mask" "F.Paste")
			(roundrect_rratio 0.25)
			(net 28 "GND")
			(pintype "passive")
		)
		(pad "2" smd roundrect
			(at 1.1 0 90)
			(size 1.2 1.3)
			(layers "F.Cu" "F.Mask" "F.Paste")
			(roundrect_rratio 0.25)
			(net 14 "P1_AVDDL")
			(pintype "passive")
		)
	)
	(footprint "antmicro-footprints:C_0402_1005Metric"
		(layer "F.Cu")
		(at 54.4 111.6 -90)
		(descr "Capacitor SMD 0402")
		(tags "capacitor SMD 0402")
		(property "Reference" "C32"
			(at 0.81 0.45 90)
			(layer "F.SilkS")
			(effects
				(font
					(size 0.7 0.7)
					(thickness 0.15)
				)
				(justify right top)
			)
		)
		(property "Value" "C_100n_0402"
			(at -1.022927 2.155213 90)
			(layer "F.Fab")
			(hide yes)
			(effects
				(font
					(size 0.7 0.7)
					(thickness 0.15)
				)
				(justify right top)
			)
		)
		(property "Datasheet" "https://www.murata.com/products/productdetail?partno=GRM155R61H104KE14%23"
			(at 0 0 90)
			(layer "F.Fab")
			(hide yes)
			(effects
				(font
					(size 1.27 1.27)
					(thickness 0.15)
				)
			)
		)
		(property "Description" "SMD Multilayer Ceramic Capacitor, 0.1 µF, 50 V, 0402 [1005 Metric], ± 10%, X5R, GRM Series"
			(at 0 0 90)
			(layer "F.Fab")
			(hide yes)
			(effects
				(font
					(size 1.27 1.27)
					(thickness 0.15)
				)
			)
		)
		(property "MPN" "GRM155R61H104KE14D"
			(at 0 0 270)
			(unlocked yes)
			(layer "F.Fab")
			(hide yes)
			(effects
				(font
					(size 1 1)
					(thickness 0.15)
				)
			)
		)
		(property "Manufacturer" "Murata"
			(at 0 0 270)
			(unlocked yes)
			(layer "F.Fab")
			(hide yes)
			(effects
				(font
					(size 1 1)
					(thickness 0.15)
				)
			)
		)
		(property "License" "Apache-2.0"
			(at 0 0 270)
			(unlocked yes)
			(layer "F.Fab")
			(hide yes)
			(effects
				(font
					(size 1 1)
					(thickness 0.15)
				)
			)
		)
		(property "Author" "Antmicro"
			(at 0 0 270)
			(unlocked yes)
			(layer "F.Fab")
			(hide yes)
			(effects
				(font
					(size 1 1)
					(thickness 0.15)
				)
			)
		)
		(property "Val" "100n"
			(at 0 0 270)
			(unlocked yes)
			(layer "F.Fab")
			(hide yes)
			(effects
				(font
					(size 1 1)
					(thickness 0.15)
				)
			)
		)
		(property "Voltage" "50V"
			(at 0 0 270)
			(unlocked yes)
			(layer "F.Fab")
			(hide yes)
			(effects
				(font
					(size 1 1)
					(thickness 0.15)
				)
			)
		)
		(property "Dielectric" "X5R"
			(at 0 0 270)
			(unlocked yes)
			(layer "F.Fab")
			(hide yes)
			(effects
				(font
					(size 1 1)
					(thickness 0.15)
				)
			)
		)
		(sheetname "/Power/")
		(sheetfile "power.kicad_sch")
		(attr smd)
		(fp_rect
			(start -0.925 -0.47)
			(end 0.925 0.47)
			(stroke
				(width 0.05)
				(type default)
			)
			(fill no)
			(layer "F.CrtYd")
		)
		(fp_line
			(start -0.494 0.248)
			(end -0.494 -0.25)
			(stroke
				(width 0.15)
				(type solid)
			)
			(layer "F.Fab")
		)
		(fp_line
			(start 0.504 0.248)
			(end -0.494 0.248)
			(stroke
				(width 0.15)
				(type solid)
			)
			(layer "F.Fab")
		)
		(fp_line
			(start -0.494 -0.25)
			(end 0.504 -0.25)
			(stroke
				(width 0.15)
				(type solid)
			)
			(layer "F.Fab")
		)
		(fp_line
			(start 0.504 -0.25)
			(end 0.504 0.248)
			(stroke
				(width 0.15)
				(type solid)
			)
			(layer "F.Fab")
		)
		(pad "1" smd roundrect
			(at -0.48 0 270)
			(size 0.59 0.64)
			(layers "F.Cu" "F.Mask" "F.Paste")
			(roundrect_rratio 0.25)
			(net 28 "GND")
			(pintype "passive")
		)
		(pad "2" smd roundrect
			(at 0.48 0 270)
			(size 0.59 0.64)
			(layers "F.Cu" "F.Mask" "F.Paste")
			(roundrect_rratio 0.25)
			(net 314 "VCC")
			(pintype "passive")
		)
	)
	(footprint "antmicro-footprints:Resonator_SMD_Murata_XRCGB_2x1.6x0.65mm"
		(layer "F.Cu")
		(at 69.3945 106.22 180)
		(property "Reference" "Y2"
			(at 2.3445 -0.61 0)
			(layer "F.SilkS")
			(effects
				(font
					(size 0.7 0.7)
					(thickness 0.15)
				)
				(justify left bottom)
			)
		)
		(property "Value" "Resonator_50MHz_XRCGE"
			(at 0 2.2 0)
			(layer "F.Fab")
			(hide yes)
			(effects
				(font
					(size 0.7 0.7)
					(thickness 0.15)
				)
				(justify right top)
			)
		)
		(property "Datasheet" "https://www.murata.com/products/productdata/8813268205598/SPEC-XRCGE50M000F5A2AR0.pdf"
			(at 0 0 0)
			(layer "F.Fab")
			(hide yes)
			(effects
				(font
					(size 1.27 1.27)
					(thickness 0.15)
				)
			)
		)
		(property "Description" "Crystal, 50 MHz, 2mm x 1.6mm, 50 ppm, 4.7 pF, 50 ppm, XRCGE Series"
			(at 0 0 0)
			(layer "F.Fab")
			(hide yes)
			(effects
				(font
					(size 1.27 1.27)
					(thickness 0.15)
				)
			)
		)
		(property "Manufacturer" "Murata"
			(at 0 0 180)
			(unlocked yes)
			(layer "F.Fab")
			(hide yes)
			(effects
				(font
					(size 1 1)
					(thickness 0.15)
				)
			)
		)
		(property "MPN" "XRCGE50M000F5A2AR0"
			(at 0 0 180)
			(unlocked yes)
			(layer "F.Fab")
			(hide yes)
			(effects
				(font
					(size 1 1)
					(thickness 0.15)
				)
			)
		)
		(property "Val" "50MHz"
			(at 0 0 180)
			(unlocked yes)
			(layer "F.Fab")
			(hide yes)
			(effects
				(font
					(size 1 1)
					(thickness 0.15)
				)
			)
		)
		(property "CLoad" "4.7pF"
			(at 0 0 180)
			(unlocked yes)
			(layer "F.Fab")
			(hide yes)
			(effects
				(font
					(size 1 1)
					(thickness 0.15)
				)
			)
		)
		(property "Author" "Antmicro"
			(at 0 0 180)
			(unlocked yes)
			(layer "F.Fab")
			(hide yes)
			(effects
				(font
					(size 1 1)
					(thickness 0.15)
				)
			)
		)
		(property "License" "Apache-2.0"
			(at 0 0 180)
			(unlocked yes)
			(layer "F.Fab")
			(hide yes)
			(effects
				(font
					(size 1 1)
					(thickness 0.15)
				)
			)
		)
		(sheetname "/X710-AT2 Misc/")
		(sheetfile "x710-at2-mics.kicad_sch")
		(attr smd)
		(fp_line
			(start 0.95 0.4)
			(end 0.95 -0.4)
			(stroke
				(width 0.15)
				(type solid)
			)
			(layer "F.SilkS")
		)
		(fp_line
			(start -0.4 1.15)
			(end 0.4 1.15)
			(stroke
				(width 0.15)
				(type solid)
			)
			(layer "F.SilkS")
		)
		(fp_line
			(start -0.4 -1.15)
			(end 0.4 -1.15)
			(stroke
				(width 0.15)
				(type solid)
			)
			(layer "F.SilkS")
		)
		(fp_line
			(start -0.95 0.4)
			(end -0.95 -0.4)
			(stroke
				(width 0.15)
				(type solid)
			)
			(layer "F.SilkS")
		)
		(fp_circle
			(center -0.95 -1.15)
			(end -0.9 -1.15)
			(stroke
				(width 0.15)
				(type solid)
			)
			(fill yes)
			(layer "F.SilkS")
		)
		(fp_rect
			(start -1.05 -1.25)
			(end 1.05 1.24)
			(stroke
				(width 0.05)
				(type solid)
			)
			(fill no)
			(layer "F.CrtYd")
		)
		(fp_rect
			(start -0.85 -1.054)
			(end 0.852 1.054)
			(stroke
				(width 0.15)
				(type solid)
			)
			(fill no)
			(layer "F.Fab")
		)
		(pad "1" smd rect
			(at -0.5 -0.675 180)
			(size 0.7 0.75)
			(layers "F.Cu" "F.Mask" "F.Paste")
			(net 76 "/X710-AT2 Misc/50MHZ_XTAL_R.+")
			(pintype "passive")
		)
		(pad "2" smd rect
			(at -0.5 0.675 180)
			(size 0.7 0.75)
			(layers "F.Cu" "F.Mask" "F.Paste")
			(net 28 "GND")
			(pinfunction "SH")
			(pintype "passive")
		)
		(pad "3" smd rect
			(at 0.5 0.675 180)
			(size 0.7 0.75)
			(layers "F.Cu" "F.Mask" "F.Paste")
			(net 77 "/X710-AT2 Misc/50MHZ_XTAL_R.-")
			(pintype "passive")
		)
		(pad "4" smd rect
			(at 0.5 -0.675 180)
			(size 0.7 0.75)
			(layers "F.Cu" "F.Mask" "F.Paste")
			(net 28 "GND")
			(pinfunction "SH")
			(pintype "passive")
		)
	)
	(footprint "antmicro-footprints:R_0402_1005Metric"
		(layer "F.Cu")
		(at 110.35 95.35 90)
		(descr "Resistor SMD 0402")
		(tags "resistor SMD 0402")
		(property "Reference" "R68"
			(at 2.9 0.35 90)
			(layer "F.SilkS")
			(effects
				(font
					(size 0.7 0.7)
					(thickness 0.15)
				)
				(justify left bottom)
			)
		)
		(property "Value" "R_10R_0402"
			(at -1.011843 1.772046 90)
			(layer "F.Fab")
			(hide yes)
			(effects
				(font
					(size 0.7 0.7)
					(thickness 0.15)
				)
				(justify left bottom)
			)
		)
		(property "Datasheet" "https://www.bourns.com/docs/product-datasheets/cr.pdf"
			(at 0 0 90)
			(layer "F.Fab")
			(hide yes)
			(effects
				(font
					(size 1.27 1.27)
					(thickness 0.15)
				)
			)
		)
		(property "Description" "SMD Chip Resistor, 10 ohm, ± 1%, 62.5 mW, 0402 [1005 Metric], Thick Film, General Purpose"
			(at 0 0 90)
			(layer "F.Fab")
			(hide yes)
			(effects
				(font
					(size 1.27 1.27)
					(thickness 0.15)
				)
			)
		)
		(property "MPN" "CR0402-FX-10R0GLF"
			(at 0 0 90)
			(unlocked yes)
			(layer "F.Fab")
			(hide yes)
			(effects
				(font
					(size 1 1)
					(thickness 0.15)
				)
			)
		)
		(property "Manufacturer" "Bourns"
			(at 0 0 90)
			(unlocked yes)
			(layer "F.Fab")
			(hide yes)
			(effects
				(font
					(size 1 1)
					(thickness 0.15)
				)
			)
		)
		(property "License" "Apache-2.0"
			(at 0 0 90)
			(unlocked yes)
			(layer "F.Fab")
			(hide yes)
			(effects
				(font
					(size 1 1)
					(thickness 0.15)
				)
			)
		)
		(property "Author" "Antmicro"
			(at 0 0 90)
			(unlocked yes)
			(layer "F.Fab")
			(hide yes)
			(effects
				(font
					(size 1 1)
					(thickness 0.15)
				)
			)
		)
		(property "Val" "10R"
			(at 0 0 90)
			(unlocked yes)
			(layer "F.Fab")
			(hide yes)
			(effects
				(font
					(size 1 1)
					(thickness 0.15)
				)
			)
		)
		(property "Tolerance" "1%"
			(at 0 0 90)
			(unlocked yes)
			(layer "F.Fab")
			(hide yes)
			(effects
				(font
					(size 1 1)
					(thickness 0.15)
				)
			)
		)
		(sheetname "/X710-AT2 10GbE/")
		(sheetfile "x710-at2-10gbe.kicad_sch")
		(attr smd)
		(fp_rect
			(start -0.925 -0.47)
			(end 0.925 0.47)
			(stroke
				(width 0.05)
				(type default)
			)
			(fill no)
			(layer "F.CrtYd")
		)
		(fp_rect
			(start -0.5 -0.25)
			(end 0.5 0.25)
			(stroke
				(width 0.15)
				(type solid)
			)
			(fill no)
			(layer "F.Fab")
		)
		(pad "1" smd roundrect
			(at -0.48 0 90)
			(size 0.59 0.64)
			(layers "F.Cu" "F.Mask" "F.Paste")
			(roundrect_rratio 0.25)
			(net 288 "/X710-AT2 10GbE/MDIO0_I2C0.MDC")
			(pintype "passive")
		)
		(pad "2" smd roundrect
			(at 0.48 0 90)
			(size 0.59 0.64)
			(layers "F.Cu" "F.Mask" "F.Paste")
			(roundrect_rratio 0.25)
			(net 130 "/X710-AT2 10GbE/MDC0_SCL0")
			(pintype "passive")
		)
	)
	(footprint "antmicro-footprints:C_0603_1608Metric_EIA"
		(layer "F.Cu")
		(at 66.7 82.100001 180)
		(descr "Capacitor SMD 0603, IPC-7351 Density Level A")
		(tags "Capacitor 0603")
		(property "Reference" "C124"
			(at -2.01 4.030001 0)
			(layer "F.SilkS")
			(effects
				(font
					(size 0.7 0.7)
					(thickness 0.15)
				)
				(justify right top)
			)
		)
		(property "Value" "C_22u_16V_0603"
			(at -1.42757 1.770288 0)
			(layer "F.Fab")
			(hide yes)
			(effects
				(font
					(size 0.7 0.7)
					(thickness 0.15)
				)
				(justify right top)
			)
		)
		(property "Datasheet" "https://product.samsungsem.com/mlcc/CL10A226MO7JZN.do"
			(at 0 0 0)
			(layer "F.Fab")
			(hide yes)
			(effects
				(font
					(size 1.27 1.27)
					(thickness 0.15)
				)
			)
		)
		(property "Description" "SMD Multilayer Ceramic Capacitor"
			(at 0 0 0)
			(layer "F.Fab")
			(hide yes)
			(effects
				(font
					(size 1.27 1.27)
					(thickness 0.15)
				)
			)
		)
		(property "MPN" "CL10A226MO7JZNC"
			(at 0 0 180)
			(unlocked yes)
			(layer "F.Fab")
			(hide yes)
			(effects
				(font
					(size 1 1)
					(thickness 0.15)
				)
			)
		)
		(property "Manufacturer" "Samsung Electro-Mechanics"
			(at 0 0 180)
			(unlocked yes)
			(layer "F.Fab")
			(hide yes)
			(effects
				(font
					(size 1 1)
					(thickness 0.15)
				)
			)
		)
		(property "License" "Apache-2.0"
			(at 0 0 180)
			(unlocked yes)
			(layer "F.Fab")
			(hide yes)
			(effects
				(font
					(size 1 1)
					(thickness 0.15)
				)
			)
		)
		(property "Author" "Antmicro"
			(at 0 0 180)
			(unlocked yes)
			(layer "F.Fab")
			(hide yes)
			(effects
				(font
					(size 1 1)
					(thickness 0.15)
				)
			)
		)
		(property "Val" "22u"
			(at 0 0 180)
			(unlocked yes)
			(layer "F.Fab")
			(hide yes)
			(effects
				(font
					(size 1 1)
					(thickness 0.15)
				)
			)
		)
		(property "Voltage" "16V"
			(at 0 0 180)
			(unlocked yes)
			(layer "F.Fab")
			(hide yes)
			(effects
				(font
					(size 1 1)
					(thickness 0.15)
				)
			)
		)
		(property "Dielectric" ""
			(at 0 0 180)
			(unlocked yes)
			(layer "F.Fab")
			(hide yes)
			(effects
				(font
					(size 1 1)
					(thickness 0.15)
				)
			)
		)
		(sheetname "/X710-AT2 power/")
		(sheetfile "x710-at2-power.kicad_sch")
		(attr smd)
		(fp_line
			(start -0.15 0.55)
			(end 0.15 0.55)
			(stroke
				(width 0.15)
				(type solid)
			)
			(layer "F.SilkS")
		)
		(fp_line
			(start -0.15 -0.55)
			(end 0.15 -0.55)
			(stroke
				(width 0.15)
				(type solid)
			)
			(layer "F.SilkS")
		)
		(fp_rect
			(start -1.25 -0.65)
			(end 1.25 0.65)
			(stroke
				(width 0.05)
				(type solid)
			)
			(fill no)
			(layer "F.CrtYd")
		)
		(fp_rect
			(start -0.8 -0.45)
			(end 0.8 0.45)
			(stroke
				(width 0.15)
				(type solid)
			)
			(fill no)
			(layer "F.Fab")
		)
		(pad "1" smd roundrect
			(at -0.7 0 180)
			(size 0.8 1.1)
			(layers "F.Cu" "F.Mask" "F.Paste")
			(roundrect_rratio 0.2)
			(net 28 "GND")
			(pintype "passive")
		)
		(pad "2" smd roundrect
			(at 0.7 0 180)
			(size 0.8 1.1)
			(layers "F.Cu" "F.Mask" "F.Paste")
			(roundrect_rratio 0.2)
			(net 9 "VCCD")
			(pintype "passive")
		)
	)
)
